(kicad_pcb
	(version 20260206)
	(generator "pcbnew")
	(generator_version "10.0")
	(general
		(thickness 1.6)
		(legacy_teardrops no)
	)
	(paper "A4")
	(title_block
		(title "9054_F0T_PDB_BD_GPU_F_V04_1213_1550_OCP.brd")
		(comment 1 "Grand Teton / footprints 285-291 of 608")
	)
	(layers
		(0 "F.Cu" signal "TOP")
		(4 "In1.Cu" signal "GND")
		(6 "In2.Cu" signal "IN1")
		(8 "In3.Cu" signal "GND1")
		(10 "In4.Cu" signal "VCC")
		(12 "In5.Cu" signal "VCC1")
		(14 "In6.Cu" signal "GND2")
		(16 "In7.Cu" signal "IN2")
		(18 "In8.Cu" signal "GND3")
		(2 "B.Cu" signal "BOTTOM")
		(9 "F.Adhes" user "F.Adhesive")
		(11 "B.Adhes" user "B.Adhesive")
		(13 "F.Paste" user "Package Geometry/Pastemask Top")
		(15 "B.Paste" user "Package Geometry/Pastemask Bottom")
		(5 "F.SilkS" user "Ref Des/Silkscreen Top")
		(7 "B.SilkS" user "Ref Des/Silkscreen Bottom")
		(1 "F.Mask" user "Board Geometry/Soldermask Top")
		(3 "B.Mask" user "Board Geometry/Soldermask Bottom")
		(17 "Dwgs.User" user "User.Drawings")
		(19 "Cmts.User" user "User.Comments")
		(21 "Eco1.User" user "User.Eco1")
		(23 "Eco2.User" user "User.Eco2")
		(25 "Edge.Cuts" user "Board Geometry/Outline")
		(27 "Margin" user)
		(31 "F.CrtYd" user "Package Geometry/Place Bound Top")
		(29 "B.CrtYd" user "Package Geometry/Place Bound Bottom")
		(35 "F.Fab" user "Ref Des/Assembly Top")
		(33 "B.Fab" user "Ref Des/Assembly Bottom")
	)
	(footprint ""
		(layer "F.Cu")
		(at 413.9184 -49.276 90)
		(property "Reference" "R420"
			(at 0 0 90)
			(layer "F.SilkS")
			(hide yes)
			(effects
				(font
					(size 1.27 1.27)
				)
			)
		)
		(property "Value" ""
			(at 0 0 90)
			(layer "F.Fab")
			(effects
				(font
					(size 1.27 1.27)
				)
			)
		)
		(duplicate_pad_numbers_are_jumpers no)
		(fp_line
			(start 0.7874 -0.4064)
			(end 0.7874 0.4064)
			(stroke
				(width 0.1524)
				(type default)
			)
			(layer "F.SilkS")
		)
		(fp_line
			(start -0.7874 -0.4064)
			(end 0.7874 -0.4064)
			(stroke
				(width 0.1524)
				(type default)
			)
			(layer "F.SilkS")
		)
		(fp_line
			(start 0.7874 0.4064)
			(end -0.7874 0.4064)
			(stroke
				(width 0.1524)
				(type default)
			)
			(layer "F.SilkS")
		)
		(fp_line
			(start -0.7874 0.4064)
			(end -0.7874 -0.4064)
			(stroke
				(width 0.1524)
				(type default)
			)
			(layer "F.SilkS")
		)
		(fp_line
			(start -0.12065 -0.305054)
			(end -0.12065 -0.2794)
			(stroke
				(width 0.1)
				(type default)
			)
			(layer "F.Fab")
		)
		(fp_line
			(start -0.67945 -0.305054)
			(end -0.12065 -0.305054)
			(stroke
				(width 0.1)
				(type default)
			)
			(layer "F.Fab")
		)
		(fp_line
			(start 0.67945 -0.3048)
			(end 0.67945 0.3048)
			(stroke
				(width 0.1)
				(type default)
			)
			(layer "F.Fab")
		)
		(fp_line
			(start 0.12065 -0.3048)
			(end 0.67945 -0.3048)
			(stroke
				(width 0.1)
				(type default)
			)
			(layer "F.Fab")
		)
		(fp_line
			(start 0.12065 -0.2794)
			(end 0.12065 -0.3048)
			(stroke
				(width 0.1)
				(type default)
			)
			(layer "F.Fab")
		)
		(fp_line
			(start -0.12065 -0.2794)
			(end 0.12065 -0.2794)
			(stroke
				(width 0.1)
				(type default)
			)
			(layer "F.Fab")
		)
		(fp_line
			(start 0.120396 0.2794)
			(end -0.12065 0.2794)
			(stroke
				(width 0.1)
				(type default)
			)
			(layer "F.Fab")
		)
		(fp_line
			(start -0.12065 0.2794)
			(end -0.12065 0.3048)
			(stroke
				(width 0.1)
				(type default)
			)
			(layer "F.Fab")
		)
		(fp_line
			(start 0.67945 0.3048)
			(end 0.120396 0.3048)
			(stroke
				(width 0.1)
				(type default)
			)
			(layer "F.Fab")
		)
		(fp_line
			(start 0.120396 0.3048)
			(end 0.120396 0.2794)
			(stroke
				(width 0.1)
				(type default)
			)
			(layer "F.Fab")
		)
		(fp_line
			(start -0.12065 0.3048)
			(end -0.67945 0.3048)
			(stroke
				(width 0.1)
				(type default)
			)
			(layer "F.Fab")
		)
		(fp_line
			(start -0.67945 0.3048)
			(end -0.67945 -0.305054)
			(stroke
				(width 0.1)
				(type default)
			)
			(layer "F.Fab")
		)
		(pad "1" smd circle
			(at -0.40005 0 90)
			(size 0 0)
			(layers "F.Cu" "F.Mask" "F.Paste")
			(net "PWRGD_P52V_HS1_4287_PG_N")
		)
		(pad "2" smd circle
			(at 0.40005 0 90)
			(size 0 0)
			(layers "F.Cu" "F.Mask" "F.Paste")
			(net "PWRGD_P52V_HS1_4287_PG_R_N")
		)
	)
	(footprint ""
		(layer "F.Cu")
		(at 47.513494 -18.542)
		(property "Reference" "PR107"
			(at -8.118094 -0.60833 0)
			(unlocked yes)
			(layer "F.SilkS")
			(effects
				(font
					(size 0.7874 0.5842)
					(thickness 0.1524)
				)
				(justify left)
			)
		)
		(property "Value" ""
			(at 0 0 0)
			(layer "F.Fab")
			(effects
				(font
					(size 1.27 1.27)
				)
			)
		)
		(duplicate_pad_numbers_are_jumpers no)
		(fp_line
			(start -3.62712 -1.8796)
			(end -3.62712 1.8796)
			(stroke
				(width 0.1524)
				(type default)
			)
			(layer "F.SilkS")
		)
		(fp_line
			(start -3.62712 1.8796)
			(end 3.62712 1.8796)
			(stroke
				(width 0.1524)
				(type default)
			)
			(layer "F.SilkS")
		)
		(fp_line
			(start 3.62712 -1.8796)
			(end -3.62712 -1.8796)
			(stroke
				(width 0.1524)
				(type default)
			)
			(layer "F.SilkS")
		)
		(fp_line
			(start 3.62712 1.8796)
			(end 3.62712 -1.8796)
			(stroke
				(width 0.1524)
				(type default)
			)
			(layer "F.SilkS")
		)
		(fp_line
			(start -3.299968 -1.700022)
			(end -3.299968 1.700022)
			(stroke
				(width 0.1)
				(type default)
			)
			(layer "F.Fab")
		)
		(fp_line
			(start -3.299968 1.700022)
			(end 3.299968 1.700022)
			(stroke
				(width 0.1)
				(type default)
			)
			(layer "F.Fab")
		)
		(fp_line
			(start 3.299968 -1.700022)
			(end -3.299968 -1.700022)
			(stroke
				(width 0.1)
				(type default)
			)
			(layer "F.Fab")
		)
		(fp_line
			(start 3.299968 1.700022)
			(end 3.299968 -1.700022)
			(stroke
				(width 0.1)
				(type default)
			)
			(layer "F.Fab")
		)
		(pad "1" smd rect
			(at -2.70002 0)
			(size 1.6002 3.5052)
			(layers "F.Cu" "F.Mask" "F.Paste")
			(net "P52V_HS2_EN_DISCHARGE_VBE_R")
		)
		(pad "2" smd rect
			(at 2.70002 0)
			(size 1.6002 3.5052)
			(layers "F.Cu" "F.Mask" "F.Paste")
			(net "GND")
		)
	)
	(footprint ""
		(layer "F.Cu")
		(at 446.151 -50.927)
		(property "Reference" "R5913"
			(at 0 0 0)
			(layer "F.SilkS")
			(hide yes)
			(effects
				(font
					(size 1.27 1.27)
				)
			)
		)
		(property "Value" ""
			(at 0 0 0)
			(layer "F.Fab")
			(effects
				(font
					(size 1.27 1.27)
				)
			)
		)
		(duplicate_pad_numbers_are_jumpers no)
		(fp_line
			(start -0.7874 -0.4064)
			(end 0.7874 -0.4064)
			(stroke
				(width 0.1524)
				(type default)
			)
			(layer "F.SilkS")
		)
		(fp_line
			(start -0.7874 0.4064)
			(end -0.7874 -0.4064)
			(stroke
				(width 0.1524)
				(type default)
			)
			(layer "F.SilkS")
		)
		(fp_line
			(start 0.7874 -0.4064)
			(end 0.7874 0.4064)
			(stroke
				(width 0.1524)
				(type default)
			)
			(layer "F.SilkS")
		)
		(fp_line
			(start 0.7874 0.4064)
			(end -0.7874 0.4064)
			(stroke
				(width 0.1524)
				(type default)
			)
			(layer "F.SilkS")
		)
		(fp_line
			(start -0.67945 -0.305054)
			(end -0.12065 -0.305054)
			(stroke
				(width 0.1)
				(type default)
			)
			(layer "F.Fab")
		)
		(fp_line
			(start -0.67945 0.3048)
			(end -0.67945 -0.305054)
			(stroke
				(width 0.1)
				(type default)
			)
			(layer "F.Fab")
		)
		(fp_line
			(start -0.12065 -0.305054)
			(end -0.12065 -0.2794)
			(stroke
				(width 0.1)
				(type default)
			)
			(layer "F.Fab")
		)
		(fp_line
			(start -0.12065 -0.2794)
			(end 0.12065 -0.2794)
			(stroke
				(width 0.1)
				(type default)
			)
			(layer "F.Fab")
		)
		(fp_line
			(start -0.12065 0.2794)
			(end -0.12065 0.3048)
			(stroke
				(width 0.1)
				(type default)
			)
			(layer "F.Fab")
		)
		(fp_line
			(start -0.12065 0.3048)
			(end -0.67945 0.3048)
			(stroke
				(width 0.1)
				(type default)
			)
			(layer "F.Fab")
		)
		(fp_line
			(start 0.120396 0.2794)
			(end -0.12065 0.2794)
			(stroke
				(width 0.1)
				(type default)
			)
			(layer "F.Fab")
		)
		(fp_line
			(start 0.120396 0.3048)
			(end 0.120396 0.2794)
			(stroke
				(width 0.1)
				(type default)
			)
			(layer "F.Fab")
		)
		(fp_line
			(start 0.12065 -0.3048)
			(end 0.67945 -0.3048)
			(stroke
				(width 0.1)
				(type default)
			)
			(layer "F.Fab")
		)
		(fp_line
			(start 0.12065 -0.2794)
			(end 0.12065 -0.3048)
			(stroke
				(width 0.1)
				(type default)
			)
			(layer "F.Fab")
		)
		(fp_line
			(start 0.67945 -0.3048)
			(end 0.67945 0.3048)
			(stroke
				(width 0.1)
				(type default)
			)
			(layer "F.Fab")
		)
		(fp_line
			(start 0.67945 0.3048)
			(end 0.120396 0.3048)
			(stroke
				(width 0.1)
				(type default)
			)
			(layer "F.Fab")
		)
		(pad "1" smd circle
			(at -0.40005 0)
			(size 0 0)
			(layers "F.Cu" "F.Mask" "F.Paste")
			(net "P3V3_AUX")
		)
		(pad "2" smd circle
			(at 0.40005 0)
			(size 0 0)
			(layers "F.Cu" "F.Mask" "F.Paste")
			(net "PWRGD_P3V3_HPDB_R_N")
		)
	)
	(footprint ""
		(layer "F.Cu")
		(at 124.483876 -18.2626)
		(property "Reference" "PQ43"
			(at 8.913114 -3.609848 0)
			(unlocked yes)
			(layer "F.SilkS")
			(effects
				(font
					(size 0.7874 0.5842)
					(thickness 0.1524)
				)
				(justify left)
			)
		)
		(property "Value" ""
			(at 0 0 0)
			(layer "F.Fab")
			(effects
				(font
					(size 1.27 1.27)
				)
			)
		)
		(duplicate_pad_numbers_are_jumpers no)
		(fp_line
			(start -7.649972 -4.99999)
			(end -7.649972 -3.3274)
			(stroke
				(width 0.1524)
				(type default)
			)
			(layer "F.SilkS")
		)
		(fp_line
			(start -7.649972 -1.7526)
			(end -7.649972 1.7526)
			(stroke
				(width 0.1524)
				(type default)
			)
			(layer "F.SilkS")
		)
		(fp_line
			(start -7.649972 3.3274)
			(end -7.649972 4.99999)
			(stroke
				(width 0.1524)
				(type default)
			)
			(layer "F.SilkS")
		)
		(fp_line
			(start -7.649972 4.99999)
			(end 5.115814 4.99999)
			(stroke
				(width 0.1524)
				(type default)
			)
			(layer "F.SilkS")
		)
		(fp_line
			(start 5.115814 -4.99999)
			(end -7.649972 -4.99999)
			(stroke
				(width 0.1524)
				(type default)
			)
			(layer "F.SilkS")
		)
		(fp_line
			(start 7.630414 4.99999)
			(end 7.649972 4.99999)
			(stroke
				(width 0.1524)
				(type default)
			)
			(layer "F.SilkS")
		)
		(fp_line
			(start 7.649972 -4.99999)
			(end 7.630414 -4.99999)
			(stroke
				(width 0.1524)
				(type default)
			)
			(layer "F.SilkS")
		)
		(fp_line
			(start 7.649972 4.99999)
			(end 7.649972 -4.99999)
			(stroke
				(width 0.1524)
				(type default)
			)
			(layer "F.SilkS")
		)
		(fp_line
			(start -7.649972 -4.99999)
			(end -7.649972 4.99999)
			(stroke
				(width 0.1)
				(type default)
			)
			(layer "F.Fab")
		)
		(fp_line
			(start -7.649972 4.99999)
			(end 7.649972 4.99999)
			(stroke
				(width 0.1)
				(type default)
			)
			(layer "F.Fab")
		)
		(fp_line
			(start 7.649972 -4.99999)
			(end -7.649972 -4.99999)
			(stroke
				(width 0.1)
				(type default)
			)
			(layer "F.Fab")
		)
		(fp_line
			(start 7.649972 4.99999)
			(end 7.649972 -4.99999)
			(stroke
				(width 0.1)
				(type default)
			)
			(layer "F.Fab")
		)
		(pad "D" smd circle
			(at 2.15011 0)
			(size 0 0)
			(layers "F.Cu" "F.Mask" "F.Paste")
			(net "P52V_HS2_DRAIN_2")
		)
		(pad "G" smd rect
			(at -7.050024 -2.54 270)
			(size 1.3208 3.0988)
			(layers "F.Cu" "F.Mask" "F.Paste")
			(net "P52V_HS2_GATE6")
		)
		(pad "S" smd rect
			(at -7.050024 2.54 270)
			(size 1.3208 3.0988)
			(layers "F.Cu" "F.Mask" "F.Paste")
			(net "P52V_HS2")
		)
		(zone
			(layer "F.Cu")
			(hatch none 0.5)
			(connect_pads
				(clearance 0)
			)
			(min_thickness 0.25)
			(keepout
				(tracks not_allowed)
				(vias allowed)
				(pads allowed)
				(copperpour not_allowed)
				(footprints allowed)
			)
			(placement
				(enabled no)
				(sheetname "")
			)
			(fill
				(thermal_gap 0.5)
				(thermal_bridge_width 0.5)
				(island_removal_mode 0)
			)
			(polygon
				(pts
					(xy 129.665476 -23.241) (xy 116.838476 -23.241) (xy 116.838476 -21.5138) (xy 119.048276 -21.5138)
					(xy 119.048276 -20.0914) (xy 116.838476 -20.0914) (xy 116.838476 -16.4338) (xy 119.048276 -16.4338)
					(xy 119.048276 -15.0114) (xy 116.838476 -15.0114) (xy 116.838476 -13.2842) (xy 129.665476 -13.2842)
					(xy 129.665476 -14.4526) (xy 123.467876 -14.4526) (xy 123.467876 -22.0726) (xy 129.665476 -22.0726)
				)
			)
		)
	)
	(footprint ""
		(layer "F.Cu")
		(at 61.92139 -119.38)
		(property "Reference" "PC37"
			(at -8.17499 -4.92633 0)
			(unlocked yes)
			(layer "F.SilkS")
			(effects
				(font
					(size 0.7874 0.5842)
					(thickness 0.1524)
				)
				(justify left)
			)
		)
		(property "Value" ""
			(at 0 0 0)
			(layer "F.Fab")
			(effects
				(font
					(size 1.27 1.27)
				)
			)
		)
		(duplicate_pad_numbers_are_jumpers no)
		(fp_line
			(start -9.253728 3.750056)
			(end 9.249918 3.750056)
			(stroke
				(width 0.1524)
				(type default)
			)
			(layer "F.SilkS")
		)
		(fp_line
			(start 0 3.750056)
			(end -9.253728 3.750056)
			(stroke
				(width 0.1524)
				(type default)
			)
			(layer "F.SilkS")
		)
		(fp_circle
			(center 0 3.750056)
			(end 9.249918 3.750056)
			(stroke
				(width 0.1524)
				(type default)
			)
			(fill no)
			(layer "F.SilkS")
		)
		(fp_poly
			(pts
				(arc
					(start 9.249918 3.750056)
					(mid 0 12.999974)
					(end -9.249918 3.750056)
				)
			)
			(stroke
				(width 0)
				(type default)
			)
			(fill yes)
			(layer "F.SilkS")
		)
		(fp_circle
			(center 0 3.750056)
			(end 9.249918 3.750056)
			(stroke
				(width 0.1)
				(type default)
			)
			(fill no)
			(layer "F.Fab")
		)
		(pad "1" thru_hole rect
			(at 0 0)
			(size 1.778 1.778)
			(drill 1.27)
			(layers "*.Cu" "*.Mask")
			(remove_unused_layers no)
			(net "P52V_HS2")
			(clearance 0)
			(padstack
				(mode front_inner_back)
				(layer "Inner"
					(shape circle)
					(size 1.778 1.778)
					(clearance 0)
				)
				(layer "B.Cu"
					(shape rect)
					(size 1.778 1.778)
					(clearance 0)
				)
			)
		)
		(pad "2" thru_hole circle
			(at 0 7.500112)
			(size 1.778 1.778)
			(drill 1.27)
			(layers "*.Cu" "*.Mask")
			(remove_unused_layers no)
			(net "GND")
			(clearance 0)
		)
	)
	(footprint ""
		(layer "F.Cu")
		(at 381.946912 -17.907254 90)
		(property "Reference" "R72"
			(at 0 0 90)
			(layer "F.SilkS")
			(hide yes)
			(effects
				(font
					(size 1.27 1.27)
				)
			)
		)
		(property "Value" ""
			(at 0 0 90)
			(layer "F.Fab")
			(effects
				(font
					(size 1.27 1.27)
				)
			)
		)
		(duplicate_pad_numbers_are_jumpers no)
		(fp_line
			(start 0.7874 -0.4064)
			(end 0.7874 0.4064)
			(stroke
				(width 0.1524)
				(type default)
			)
			(layer "F.SilkS")
		)
		(fp_line
			(start -0.7874 -0.4064)
			(end 0.7874 -0.4064)
			(stroke
				(width 0.1524)
				(type default)
			)
			(layer "F.SilkS")
		)
		(fp_line
			(start 0.7874 0.4064)
			(end -0.7874 0.4064)
			(stroke
				(width 0.1524)
				(type default)
			)
			(layer "F.SilkS")
		)
		(fp_line
			(start -0.7874 0.4064)
			(end -0.7874 -0.4064)
			(stroke
				(width 0.1524)
				(type default)
			)
			(layer "F.SilkS")
		)
		(fp_line
			(start -0.12065 -0.305054)
			(end -0.12065 -0.2794)
			(stroke
				(width 0.1)
				(type default)
			)
			(layer "F.Fab")
		)
		(fp_line
			(start -0.67945 -0.305054)
			(end -0.12065 -0.305054)
			(stroke
				(width 0.1)
				(type default)
			)
			(layer "F.Fab")
		)
		(fp_line
			(start 0.67945 -0.3048)
			(end 0.67945 0.3048)
			(stroke
				(width 0.1)
				(type default)
			)
			(layer "F.Fab")
		)
		(fp_line
			(start 0.12065 -0.3048)
			(end 0.67945 -0.3048)
			(stroke
				(width 0.1)
				(type default)
			)
			(layer "F.Fab")
		)
		(fp_line
			(start 0.12065 -0.2794)
			(end 0.12065 -0.3048)
			(stroke
				(width 0.1)
				(type default)
			)
			(layer "F.Fab")
		)
		(fp_line
			(start -0.12065 -0.2794)
			(end 0.12065 -0.2794)
			(stroke
				(width 0.1)
				(type default)
			)
			(layer "F.Fab")
		)
		(fp_line
			(start 0.120396 0.2794)
			(end -0.12065 0.2794)
			(stroke
				(width 0.1)
				(type default)
			)
			(layer "F.Fab")
		)
		(fp_line
			(start -0.12065 0.2794)
			(end -0.12065 0.3048)
			(stroke
				(width 0.1)
				(type default)
			)
			(layer "F.Fab")
		)
		(fp_line
			(start 0.67945 0.3048)
			(end 0.120396 0.3048)
			(stroke
				(width 0.1)
				(type default)
			)
			(layer "F.Fab")
		)
		(fp_line
			(start 0.120396 0.3048)
			(end 0.120396 0.2794)
			(stroke
				(width 0.1)
				(type default)
			)
			(layer "F.Fab")
		)
		(fp_line
			(start -0.12065 0.3048)
			(end -0.67945 0.3048)
			(stroke
				(width 0.1)
				(type default)
			)
			(layer "F.Fab")
		)
		(fp_line
			(start -0.67945 0.3048)
			(end -0.67945 -0.305054)
			(stroke
				(width 0.1)
				(type default)
			)
			(layer "F.Fab")
		)
		(pad "1" smd circle
			(at -0.40005 0 90)
			(size 0 0)
			(layers "F.Cu" "F.Mask" "F.Paste")
			(net "FAN_PWR_EN_0_R")
		)
		(pad "2" smd circle
			(at 0.40005 0 90)
			(size 0 0)
			(layers "F.Cu" "F.Mask" "F.Paste")
			(net "FAN_PWR_EN_BUF")
		)
	)
	(footprint ""
		(layer "F.Cu")
		(at 222.6564 -91.948 180)
		(property "Reference" "PR473"
			(at 0 0 180)
			(layer "F.SilkS")
			(hide yes)
			(effects
				(font
					(size 1.27 1.27)
				)
			)
		)
		(property "Value" ""
			(at 0 0 180)
			(layer "F.Fab")
			(effects
				(font
					(size 1.27 1.27)
				)
			)
		)
		(duplicate_pad_numbers_are_jumpers no)
		(fp_line
			(start 0.7874 0.4064)
			(end -0.7874 0.4064)
			(stroke
				(width 0.1524)
				(type default)
			)
			(layer "F.SilkS")
		)
		(fp_line
			(start 0.7874 -0.4064)
			(end 0.7874 0.4064)
			(stroke
				(width 0.1524)
				(type default)
			)
			(layer "F.SilkS")
		)
		(fp_line
			(start -0.7874 0.4064)
			(end -0.7874 -0.4064)
			(stroke
				(width 0.1524)
				(type default)
			)
			(layer "F.SilkS")
		)
		(fp_line
			(start -0.7874 -0.4064)
			(end 0.7874 -0.4064)
			(stroke
				(width 0.1524)
				(type default)
			)
			(layer "F.SilkS")
		)
		(fp_line
			(start 0.67945 0.3048)
			(end 0.120396 0.3048)
			(stroke
				(width 0.1)
				(type default)
			)
			(layer "F.Fab")
		)
		(fp_line
			(start 0.67945 -0.3048)
			(end 0.67945 0.3048)
			(stroke
				(width 0.1)
				(type default)
			)
			(layer "F.Fab")
		)
		(fp_line
			(start 0.12065 -0.2794)
			(end 0.12065 -0.3048)
			(stroke
				(width 0.1)
				(type default)
			)
			(layer "F.Fab")
		)
		(fp_line
			(start 0.12065 -0.3048)
			(end 0.67945 -0.3048)
			(stroke
				(width 0.1)
				(type default)
			)
			(layer "F.Fab")
		)
		(fp_line
			(start 0.120396 0.3048)
			(end 0.120396 0.2794)
			(stroke
				(width 0.1)
				(type default)
			)
			(layer "F.Fab")
		)
		(fp_line
			(start 0.120396 0.2794)
			(end -0.12065 0.2794)
			(stroke
				(width 0.1)
				(type default)
			)
			(layer "F.Fab")
		)
		(fp_line
			(start -0.12065 0.3048)
			(end -0.67945 0.3048)
			(stroke
				(width 0.1)
				(type default)
			)
			(layer "F.Fab")
		)
		(fp_line
			(start -0.12065 0.2794)
			(end -0.12065 0.3048)
			(stroke
				(width 0.1)
				(type default)
			)
			(layer "F.Fab")
		)
		(fp_line
			(start -0.12065 -0.2794)
			(end 0.12065 -0.2794)
			(stroke
				(width 0.1)
				(type default)
			)
			(layer "F.Fab")
		)
		(fp_line
			(start -0.12065 -0.305054)
			(end -0.12065 -0.2794)
			(stroke
				(width 0.1)
				(type default)
			)
			(layer "F.Fab")
		)
		(fp_line
			(start -0.67945 0.3048)
			(end -0.67945 -0.305054)
			(stroke
				(width 0.1)
				(type default)
			)
			(layer "F.Fab")
		)
		(fp_line
			(start -0.67945 -0.305054)
			(end -0.12065 -0.305054)
			(stroke
				(width 0.1)
				(type default)
			)
			(layer "F.Fab")
		)
		(pad "1" smd circle
			(at -0.40005 0 180)
			(size 0 0)
			(layers "F.Cu" "F.Mask" "F.Paste")
			(net "SMB_P52V_PDB_SCL")
		)
		(pad "2" smd circle
			(at 0.40005 0 180)
			(size 0 0)
			(layers "F.Cu" "F.Mask" "F.Paste")
			(net "SMB_P52V_PDB_DEBUG_SCL")
		)
	)
)
